(kicad_pcb
	(version 20260206)
	(generator "pcbnew")
	(generator_version "10.0")
	(general
		(thickness 1.6)
		(legacy_teardrops no)
	)
	(paper "A4")
	(title_block
		(title "01162023_DA0F0TEBIF0_F0T_Expander_BD_F_brd_V02_OCP.brd")
		(comment 1 "Grand Teton / footprints 5259-5266 of 9728")
	)
	(layers
		(0 "F.Cu" signal "TOP")
		(4 "In1.Cu" signal "GND")
		(6 "In2.Cu" signal "VCC")
		(8 "In3.Cu" signal "VCC1")
		(10 "In4.Cu" signal "GND1")
		(12 "In5.Cu" signal "IN1")
		(14 "In6.Cu" signal "GND2")
		(16 "In7.Cu" signal "IN2")
		(18 "In8.Cu" signal "GND3")
		(20 "In9.Cu" signal "IN3")
		(22 "In10.Cu" signal "GND4")
		(24 "In11.Cu" signal "IN4")
		(26 "In12.Cu" signal "GND5")
		(28 "In13.Cu" signal "IN5")
		(30 "In14.Cu" signal "GND6")
		(32 "In15.Cu" signal "IN6")
		(34 "In16.Cu" signal "GND7")
		(2 "B.Cu" signal "BOTTOM")
		(9 "F.Adhes" user "F.Adhesive")
		(11 "B.Adhes" user "B.Adhesive")
		(13 "F.Paste" user "Package Geometry/Pastemask Top")
		(15 "B.Paste" user "Package Geometry/Pastemask Bottom")
		(5 "F.SilkS" user "Ref Des/Silkscreen Top")
		(7 "B.SilkS" user "Ref Des/Silkscreen Bottom")
		(1 "F.Mask" user "Board Geometry/Soldermask Top")
		(3 "B.Mask" user "Board Geometry/Soldermask Bottom")
		(17 "Dwgs.User" user "User.Drawings")
		(19 "Cmts.User" user "User.Comments")
		(21 "Eco1.User" user "User.Eco1")
		(23 "Eco2.User" user "User.Eco2")
		(25 "Edge.Cuts" user "Board Geometry/Outline")
		(27 "Margin" user)
		(31 "F.CrtYd" user "Package Geometry/Place Bound Top")
		(29 "B.CrtYd" user "Package Geometry/Place Bound Bottom")
		(35 "F.Fab" user "Ref Des/Assembly Top")
		(33 "B.Fab" user "Ref Des/Assembly Bottom")
	)
	(footprint ""
		(layer "F.Cu")
		(at 165.269672 -343.952322 90)
		(property "Reference" "C2514"
			(at 0 0 90)
			(layer "F.SilkS")
			(hide yes)
			(effects
				(font
					(size 1.27 1.27)
				)
			)
		)
		(property "Value" ""
			(at 0 0 90)
			(layer "F.Fab")
			(effects
				(font
					(size 1.27 1.27)
				)
			)
		)
		(duplicate_pad_numbers_are_jumpers no)
		(fp_line
			(start 0.299974 -0.150114)
			(end 0.299974 0.150114)
			(stroke
				(width 0.1)
				(type default)
			)
			(layer "F.Fab")
		)
		(fp_line
			(start -0.299974 -0.150114)
			(end 0.299974 -0.150114)
			(stroke
				(width 0.1)
				(type default)
			)
			(layer "F.Fab")
		)
		(fp_line
			(start 0.299974 0.150114)
			(end -0.299974 0.150114)
			(stroke
				(width 0.1)
				(type default)
			)
			(layer "F.Fab")
		)
		(fp_line
			(start -0.299974 0.150114)
			(end -0.299974 -0.150114)
			(stroke
				(width 0.1)
				(type default)
			)
			(layer "F.Fab")
		)
		(pad "1" smd rect
			(at -0.2667 0 90)
			(size 0.3048 0.381)
			(layers "F.Cu" "F.Mask" "F.Paste")
			(net "P5E_PEX1_STN4_TX_DP<78>")
		)
		(pad "2" smd rect
			(at 0.2667 0 90)
			(size 0.3048 0.381)
			(layers "F.Cu" "F.Mask" "F.Paste")
			(net "P5E_PEX1_STN4_TX_C_DP<78>")
		)
	)
	(footprint ""
		(layer "F.Cu")
		(at 56.526684 -53.697124 -90)
		(property "Reference" "PC534"
			(at 0 0 270)
			(layer "F.SilkS")
			(hide yes)
			(effects
				(font
					(size 1.27 1.27)
				)
			)
		)
		(property "Value" ""
			(at 0 0 270)
			(layer "F.Fab")
			(effects
				(font
					(size 1.27 1.27)
				)
			)
		)
		(duplicate_pad_numbers_are_jumpers no)
		(fp_line
			(start -0.7874 0.4064)
			(end -0.7874 -0.4064)
			(stroke
				(width 0.1524)
				(type default)
			)
			(layer "F.SilkS")
		)
		(fp_line
			(start 0.7874 0.4064)
			(end -0.7874 0.4064)
			(stroke
				(width 0.1524)
				(type default)
			)
			(layer "F.SilkS")
		)
		(fp_line
			(start -0.7874 -0.4064)
			(end 0.7874 -0.4064)
			(stroke
				(width 0.1524)
				(type default)
			)
			(layer "F.SilkS")
		)
		(fp_line
			(start 0.7874 -0.4064)
			(end 0.7874 0.4064)
			(stroke
				(width 0.1524)
				(type default)
			)
			(layer "F.SilkS")
		)
		(fp_line
			(start -0.67945 0.3048)
			(end -0.67945 -0.305054)
			(stroke
				(width 0.1)
				(type default)
			)
			(layer "F.Fab")
		)
		(fp_line
			(start -0.12065 0.3048)
			(end -0.67945 0.3048)
			(stroke
				(width 0.1)
				(type default)
			)
			(layer "F.Fab")
		)
		(fp_line
			(start 0.120396 0.3048)
			(end 0.120396 0.2794)
			(stroke
				(width 0.1)
				(type default)
			)
			(layer "F.Fab")
		)
		(fp_line
			(start 0.67945 0.3048)
			(end 0.120396 0.3048)
			(stroke
				(width 0.1)
				(type default)
			)
			(layer "F.Fab")
		)
		(fp_line
			(start -0.12065 0.2794)
			(end -0.12065 0.3048)
			(stroke
				(width 0.1)
				(type default)
			)
			(layer "F.Fab")
		)
		(fp_line
			(start 0.120396 0.2794)
			(end -0.12065 0.2794)
			(stroke
				(width 0.1)
				(type default)
			)
			(layer "F.Fab")
		)
		(fp_line
			(start -0.12065 -0.2794)
			(end 0.12065 -0.2794)
			(stroke
				(width 0.1)
				(type default)
			)
			(layer "F.Fab")
		)
		(fp_line
			(start 0.12065 -0.2794)
			(end 0.12065 -0.3048)
			(stroke
				(width 0.1)
				(type default)
			)
			(layer "F.Fab")
		)
		(fp_line
			(start 0.12065 -0.3048)
			(end 0.67945 -0.3048)
			(stroke
				(width 0.1)
				(type default)
			)
			(layer "F.Fab")
		)
		(fp_line
			(start 0.67945 -0.3048)
			(end 0.67945 0.3048)
			(stroke
				(width 0.1)
				(type default)
			)
			(layer "F.Fab")
		)
		(fp_line
			(start -0.67945 -0.305054)
			(end -0.12065 -0.305054)
			(stroke
				(width 0.1)
				(type default)
			)
			(layer "F.Fab")
		)
		(fp_line
			(start -0.12065 -0.305054)
			(end -0.12065 -0.2794)
			(stroke
				(width 0.1)
				(type default)
			)
			(layer "F.Fab")
		)
		(pad "1" smd circle
			(at -0.40005 0 270)
			(size 0 0)
			(layers "F.Cu" "F.Mask" "F.Paste")
			(net "P3V3_AUX")
		)
		(pad "2" smd circle
			(at 0.40005 0 270)
			(size 0 0)
			(layers "F.Cu" "F.Mask" "F.Paste")
			(net "GND")
		)
	)
	(footprint ""
		(layer "F.Cu")
		(at 385.548124 -101.095302)
		(property "Reference" "C694"
			(at 0 0 0)
			(layer "F.SilkS")
			(hide yes)
			(effects
				(font
					(size 1.27 1.27)
				)
			)
		)
		(property "Value" ""
			(at 0 0 0)
			(layer "F.Fab")
			(effects
				(font
					(size 1.27 1.27)
				)
			)
		)
		(duplicate_pad_numbers_are_jumpers no)
		(fp_line
			(start -0.299974 -0.150114)
			(end 0.299974 -0.150114)
			(stroke
				(width 0.1)
				(type default)
			)
			(layer "F.Fab")
		)
		(fp_line
			(start -0.299974 0.150114)
			(end -0.299974 -0.150114)
			(stroke
				(width 0.1)
				(type default)
			)
			(layer "F.Fab")
		)
		(fp_line
			(start 0.299974 -0.150114)
			(end 0.299974 0.150114)
			(stroke
				(width 0.1)
				(type default)
			)
			(layer "F.Fab")
		)
		(fp_line
			(start 0.299974 0.150114)
			(end -0.299974 0.150114)
			(stroke
				(width 0.1)
				(type default)
			)
			(layer "F.Fab")
		)
		(pad "1" smd rect
			(at -0.2667 0)
			(size 0.3048 0.381)
			(layers "F.Cu" "F.Mask" "F.Paste")
			(net "P5E_PEX3_STN1_TX_DN<17>")
		)
		(pad "2" smd rect
			(at 0.2667 0)
			(size 0.3048 0.381)
			(layers "F.Cu" "F.Mask" "F.Paste")
			(net "P5E_PEX3_STN1_TX_C_DN<17>")
		)
	)
	(footprint ""
		(layer "F.Cu")
		(at 376.34926 -287.395412 -90)
		(property "Reference" "C3574"
			(at 0 0 270)
			(layer "F.SilkS")
			(hide yes)
			(effects
				(font
					(size 1.27 1.27)
				)
			)
		)
		(property "Value" ""
			(at 0 0 270)
			(layer "F.Fab")
			(effects
				(font
					(size 1.27 1.27)
				)
			)
		)
		(duplicate_pad_numbers_are_jumpers no)
		(fp_line
			(start -0.299974 0.150114)
			(end -0.299974 -0.150114)
			(stroke
				(width 0.1)
				(type default)
			)
			(layer "F.Fab")
		)
		(fp_line
			(start 0.299974 0.150114)
			(end -0.299974 0.150114)
			(stroke
				(width 0.1)
				(type default)
			)
			(layer "F.Fab")
		)
		(fp_line
			(start -0.299974 -0.150114)
			(end 0.299974 -0.150114)
			(stroke
				(width 0.1)
				(type default)
			)
			(layer "F.Fab")
		)
		(fp_line
			(start 0.299974 -0.150114)
			(end 0.299974 0.150114)
			(stroke
				(width 0.1)
				(type default)
			)
			(layer "F.Fab")
		)
		(pad "1" smd rect
			(at -0.2667 0 270)
			(size 0.3048 0.381)
			(layers "F.Cu" "F.Mask" "F.Paste")
			(net "P1V8_PLL0_PEX3")
		)
		(pad "2" smd rect
			(at 0.2667 0 270)
			(size 0.3048 0.381)
			(layers "F.Cu" "F.Mask" "F.Paste")
			(net "GND")
		)
	)
	(footprint ""
		(layer "F.Cu")
		(at 294.691816 -161.881566 90)
		(property "Reference" "Q121"
			(at -0.032766 -1.930146 90)
			(unlocked yes)
			(layer "F.SilkS")
			(effects
				(font
					(size 0.7874 0.5842)
					(thickness 0.1524)
				)
			)
		)
		(property "Value" ""
			(at 0 0 90)
			(layer "F.Fab")
			(effects
				(font
					(size 1.27 1.27)
				)
			)
		)
		(duplicate_pad_numbers_are_jumpers no)
		(fp_line
			(start 1.376172 -1.199896)
			(end 1.376172 1.199896)
			(stroke
				(width 0.1524)
				(type default)
			)
			(layer "F.SilkS")
		)
		(fp_line
			(start 0.508 -1.199896)
			(end 1.376172 -1.199896)
			(stroke
				(width 0.1524)
				(type default)
			)
			(layer "F.SilkS")
		)
		(fp_line
			(start -0.508 -1.199896)
			(end 0 -0.762)
			(stroke
				(width 0.1524)
				(type default)
			)
			(layer "F.SilkS")
		)
		(fp_line
			(start -1.376172 -1.199896)
			(end -0.508 -1.199896)
			(stroke
				(width 0.1524)
				(type default)
			)
			(layer "F.SilkS")
		)
		(fp_line
			(start 0 -0.762)
			(end 0.508 -1.199896)
			(stroke
				(width 0.1524)
				(type default)
			)
			(layer "F.SilkS")
		)
		(fp_line
			(start 1.376172 1.199896)
			(end -1.376172 1.199896)
			(stroke
				(width 0.1524)
				(type default)
			)
			(layer "F.SilkS")
		)
		(fp_line
			(start -1.376172 1.199896)
			(end -1.376172 -1.199896)
			(stroke
				(width 0.1524)
				(type default)
			)
			(layer "F.SilkS")
		)
		(fp_poly
			(pts
				(xy -1.537208 -1.13538) (xy -1.806702 -1.943608) (xy -2.345436 -1.404874)
			)
			(stroke
				(width 0)
				(type default)
			)
			(fill yes)
			(layer "F.SilkS")
		)
		(fp_line
			(start 0.674878 -1.100074)
			(end 0.674878 1.100074)
			(stroke
				(width 0.1)
				(type default)
			)
			(layer "F.Fab")
		)
		(fp_line
			(start -0.674878 -1.100074)
			(end 0.674878 -1.100074)
			(stroke
				(width 0.1)
				(type default)
			)
			(layer "F.Fab")
		)
		(fp_line
			(start 0.674878 1.100074)
			(end -0.674878 1.100074)
			(stroke
				(width 0.1)
				(type default)
			)
			(layer "F.Fab")
		)
		(fp_line
			(start -0.674878 1.100074)
			(end -0.674878 -1.100074)
			(stroke
				(width 0.1)
				(type default)
			)
			(layer "F.Fab")
		)
		(fp_poly
			(pts
				(xy -1.4605 -0.7493) (xy -2.2225 -1.1303) (xy -2.2225 -0.3683)
			)
			(stroke
				(width 0)
				(type default)
			)
			(fill yes)
			(layer "F.Fab")
		)
		(pad "1" smd rect
			(at -0.899922 -0.750062)
			(size 0.6096 0.6096)
			(layers "F.Cu" "F.Mask" "F.Paste")
			(net "GND")
		)
		(pad "2" smd rect
			(at -0.899922 0)
			(size 0.4064 0.6096)
			(layers "F.Cu" "F.Mask" "F.Paste")
			(net "FM_SYS_THROTTLE_NIC4")
		)
		(pad "3" smd rect
			(at -0.899922 0.750062)
			(size 0.6096 0.6096)
			(layers "F.Cu" "F.Mask" "F.Paste")
			(net "NIC5_PWRBRK_N")
		)
		(pad "4" smd rect
			(at 0.899922 0.750062)
			(size 0.6096 0.6096)
			(layers "F.Cu" "F.Mask" "F.Paste")
			(net "GND")
		)
		(pad "5" smd rect
			(at 0.899922 0)
			(size 0.4064 0.6096)
			(layers "F.Cu" "F.Mask" "F.Paste")
			(net "FM_SYS_THROTTLE_NIC5")
		)
		(pad "6" smd rect
			(at 0.899922 -0.750062)
			(size 0.6096 0.6096)
			(layers "F.Cu" "F.Mask" "F.Paste")
			(net "NIC4_PWRBRK_N")
		)
	)
	(footprint ""
		(layer "F.Cu")
		(at 200.691496 -114.42954)
		(property "Reference" "R186"
			(at 0 0 0)
			(layer "F.SilkS")
			(hide yes)
			(effects
				(font
					(size 1.27 1.27)
				)
			)
		)
		(property "Value" ""
			(at 0 0 0)
			(layer "F.Fab")
			(effects
				(font
					(size 1.27 1.27)
				)
			)
		)
		(duplicate_pad_numbers_are_jumpers no)
		(fp_line
			(start -0.7874 -0.4064)
			(end 0.7874 -0.4064)
			(stroke
				(width 0.1524)
				(type default)
			)
			(layer "F.SilkS")
		)
		(fp_line
			(start -0.7874 0.4064)
			(end -0.7874 -0.4064)
			(stroke
				(width 0.1524)
				(type default)
			)
			(layer "F.SilkS")
		)
		(fp_line
			(start 0.7874 -0.4064)
			(end 0.7874 0.4064)
			(stroke
				(width 0.1524)
				(type default)
			)
			(layer "F.SilkS")
		)
		(fp_line
			(start 0.7874 0.4064)
			(end -0.7874 0.4064)
			(stroke
				(width 0.1524)
				(type default)
			)
			(layer "F.SilkS")
		)
		(fp_line
			(start -0.67945 -0.305054)
			(end -0.12065 -0.305054)
			(stroke
				(width 0.1)
				(type default)
			)
			(layer "F.Fab")
		)
		(fp_line
			(start -0.67945 0.3048)
			(end -0.67945 -0.305054)
			(stroke
				(width 0.1)
				(type default)
			)
			(layer "F.Fab")
		)
		(fp_line
			(start -0.12065 -0.305054)
			(end -0.12065 -0.2794)
			(stroke
				(width 0.1)
				(type default)
			)
			(layer "F.Fab")
		)
		(fp_line
			(start -0.12065 -0.2794)
			(end 0.12065 -0.2794)
			(stroke
				(width 0.1)
				(type default)
			)
			(layer "F.Fab")
		)
		(fp_line
			(start -0.12065 0.2794)
			(end -0.12065 0.3048)
			(stroke
				(width 0.1)
				(type default)
			)
			(layer "F.Fab")
		)
		(fp_line
			(start -0.12065 0.3048)
			(end -0.67945 0.3048)
			(stroke
				(width 0.1)
				(type default)
			)
			(layer "F.Fab")
		)
		(fp_line
			(start 0.120396 0.2794)
			(end -0.12065 0.2794)
			(stroke
				(width 0.1)
				(type default)
			)
			(layer "F.Fab")
		)
		(fp_line
			(start 0.120396 0.3048)
			(end 0.120396 0.2794)
			(stroke
				(width 0.1)
				(type default)
			)
			(layer "F.Fab")
		)
		(fp_line
			(start 0.12065 -0.3048)
			(end 0.67945 -0.3048)
			(stroke
				(width 0.1)
				(type default)
			)
			(layer "F.Fab")
		)
		(fp_line
			(start 0.12065 -0.2794)
			(end 0.12065 -0.3048)
			(stroke
				(width 0.1)
				(type default)
			)
			(layer "F.Fab")
		)
		(fp_line
			(start 0.67945 -0.3048)
			(end 0.67945 0.3048)
			(stroke
				(width 0.1)
				(type default)
			)
			(layer "F.Fab")
		)
		(fp_line
			(start 0.67945 0.3048)
			(end 0.120396 0.3048)
			(stroke
				(width 0.1)
				(type default)
			)
			(layer "F.Fab")
		)
		(pad "1" smd circle
			(at -0.40005 0)
			(size 0 0)
			(layers "F.Cu" "F.Mask" "F.Paste")
			(net "NIC3_BIF2_N")
		)
		(pad "2" smd circle
			(at 0.40005 0)
			(size 0 0)
			(layers "F.Cu" "F.Mask" "F.Paste")
			(net "P3V3_AUX")
		)
	)
	(footprint ""
		(layer "F.Cu")
		(at 128.966214 -214.540846)
		(property "Reference" "C2609"
			(at 0 0 0)
			(layer "F.SilkS")
			(hide yes)
			(effects
				(font
					(size 1.27 1.27)
				)
			)
		)
		(property "Value" ""
			(at 0 0 0)
			(layer "F.Fab")
			(effects
				(font
					(size 1.27 1.27)
				)
			)
		)
		(duplicate_pad_numbers_are_jumpers no)
		(fp_line
			(start -0.7874 -0.4064)
			(end 0.7874 -0.4064)
			(stroke
				(width 0.1524)
				(type default)
			)
			(layer "F.SilkS")
		)
		(fp_line
			(start -0.7874 0.4064)
			(end -0.7874 -0.4064)
			(stroke
				(width 0.1524)
				(type default)
			)
			(layer "F.SilkS")
		)
		(fp_line
			(start 0.7874 -0.4064)
			(end 0.7874 0.4064)
			(stroke
				(width 0.1524)
				(type default)
			)
			(layer "F.SilkS")
		)
		(fp_line
			(start 0.7874 0.4064)
			(end -0.7874 0.4064)
			(stroke
				(width 0.1524)
				(type default)
			)
			(layer "F.SilkS")
		)
		(fp_line
			(start -0.67945 -0.305054)
			(end -0.12065 -0.305054)
			(stroke
				(width 0.1)
				(type default)
			)
			(layer "F.Fab")
		)
		(fp_line
			(start -0.67945 0.3048)
			(end -0.67945 -0.305054)
			(stroke
				(width 0.1)
				(type default)
			)
			(layer "F.Fab")
		)
		(fp_line
			(start -0.12065 -0.305054)
			(end -0.12065 -0.2794)
			(stroke
				(width 0.1)
				(type default)
			)
			(layer "F.Fab")
		)
		(fp_line
			(start -0.12065 -0.2794)
			(end 0.12065 -0.2794)
			(stroke
				(width 0.1)
				(type default)
			)
			(layer "F.Fab")
		)
		(fp_line
			(start -0.12065 0.2794)
			(end -0.12065 0.3048)
			(stroke
				(width 0.1)
				(type default)
			)
			(layer "F.Fab")
		)
		(fp_line
			(start -0.12065 0.3048)
			(end -0.67945 0.3048)
			(stroke
				(width 0.1)
				(type default)
			)
			(layer "F.Fab")
		)
		(fp_line
			(start 0.120396 0.2794)
			(end -0.12065 0.2794)
			(stroke
				(width 0.1)
				(type default)
			)
			(layer "F.Fab")
		)
		(fp_line
			(start 0.120396 0.3048)
			(end 0.120396 0.2794)
			(stroke
				(width 0.1)
				(type default)
			)
			(layer "F.Fab")
		)
		(fp_line
			(start 0.12065 -0.3048)
			(end 0.67945 -0.3048)
			(stroke
				(width 0.1)
				(type default)
			)
			(layer "F.Fab")
		)
		(fp_line
			(start 0.12065 -0.2794)
			(end 0.12065 -0.3048)
			(stroke
				(width 0.1)
				(type default)
			)
			(layer "F.Fab")
		)
		(fp_line
			(start 0.67945 -0.3048)
			(end 0.67945 0.3048)
			(stroke
				(width 0.1)
				(type default)
			)
			(layer "F.Fab")
		)
		(fp_line
			(start 0.67945 0.3048)
			(end 0.120396 0.3048)
			(stroke
				(width 0.1)
				(type default)
			)
			(layer "F.Fab")
		)
		(pad "1" smd circle
			(at -0.40005 0)
			(size 0 0)
			(layers "F.Cu" "F.Mask" "F.Paste")
			(net "GND")
		)
		(pad "2" smd circle
			(at 0.40005 0)
			(size 0 0)
			(layers "F.Cu" "F.Mask" "F.Paste")
			(net "P1V8_PEX")
		)
	)
	(footprint ""
		(layer "F.Cu")
		(at 67.987926 -45.704252 90)
		(property "Reference" "R527"
			(at 0 0 90)
			(layer "F.SilkS")
			(hide yes)
			(effects
				(font
					(size 1.27 1.27)
				)
			)
		)
		(property "Value" ""
			(at 0 0 90)
			(layer "F.Fab")
			(effects
				(font
					(size 1.27 1.27)
				)
			)
		)
		(duplicate_pad_numbers_are_jumpers no)
		(fp_line
			(start 3.937508 -1.8796)
			(end -3.937508 -1.8796)
			(stroke
				(width 0.1524)
				(type default)
			)
			(layer "F.SilkS")
		)
		(fp_line
			(start -3.937508 -1.8796)
			(end -3.937508 1.8796)
			(stroke
				(width 0.1524)
				(type default)
			)
			(layer "F.SilkS")
		)
		(fp_line
			(start 3.937508 1.8796)
			(end 3.937508 -1.8796)
			(stroke
				(width 0.1524)
				(type default)
			)
			(layer "F.SilkS")
		)
		(fp_line
			(start -3.937508 1.8796)
			(end 3.937508 1.8796)
			(stroke
				(width 0.1524)
				(type default)
			)
			(layer "F.SilkS")
		)
		(fp_line
			(start 3.275076 -1.674876)
			(end -3.275076 -1.674876)
			(stroke
				(width 0.1)
				(type default)
			)
			(layer "F.Fab")
		)
		(fp_line
			(start -3.275076 -1.674876)
			(end -3.275076 1.674876)
			(stroke
				(width 0.1)
				(type default)
			)
			(layer "F.Fab")
		)
		(fp_line
			(start 3.275076 1.674876)
			(end 3.275076 -1.674876)
			(stroke
				(width 0.1)
				(type default)
			)
			(layer "F.Fab")
		)
		(fp_line
			(start -3.275076 1.674876)
			(end 3.275076 1.674876)
			(stroke
				(width 0.1)
				(type default)
			)
			(layer "F.Fab")
		)
		(pad "1" smd rect
			(at -2.350008 0 90)
			(size 2.921 3.5052)
			(layers "F.Cu" "F.Mask" "F.Paste")
			(net "P12V_SSD2")
		)
		(pad "2" smd rect
			(at 2.350008 0 90)
			(size 2.921 3.5052)
			(layers "F.Cu" "F.Mask" "F.Paste")
			(net "P12V_SSD2_R")
		)
	)
)
